# BASEBOARD_FAB2 (Tioga Pass) — schematic parts with pin connectivity, parts 4665–4665 of 4751; source: Cadence DE-HDL packaged netlist (pstxprt.dat, pstxnet.dat, pstchip.dat)

U5D1  SKX_EXT_B  IC  pkg BGA1  page 21  (pins 2713-3051 of 3647)
  DW46  RSVD(22)  BI  = TP_CPU0_RSVD_22
  DW48  DDR3_MA(13)  OUT  = M_D_MA<13>
  DW50  DDR4_CS_N(4)  OUT  = M_E_CS_N<4>
  DW52  DDR4_MA(0)  OUT  = M_E_MA<0>
  DW54  DDR3_MA(10)  OUT  = M_D_MA<10>
  DW56  DDR3_CLK_DN(2)  OUT  = M_D_CLK_DN<2>
  DW58  DDR4_MA(1)  OUT  = M_E_MA<1>
  DW60  DDR3_ACT_N  OUT  = M_D_ACT_N
  DW62  DDR3_BG(1)  OUT  = M_D_BG<1>
  DW64  VSS(65)  GROUND  = GND
  DW66  VSS(64)  GROUND  = GND
  DW68  VSS(63)  GROUND  = GND
  DW70  VSS(62)  GROUND  = GND
  DW72  VSS(61)  GROUND  = GND
  DW74  VSS(60)  GROUND  = GND
  DW76  VSS(59)  GROUND  = GND
  DW78  DDR4_DQ(22)  BI  = M_E_DQ<22>
  DW80  DDR4_DQ(16)  BI  = M_E_DQ<16>
  DW82  VSS(57)  GROUND  = GND
  DW84  VSS(56)  GROUND  = GND
  DY3  RSVD(21)  BI  = TP_CPU0_RSVD_21
  DY5  VSS(55)  GROUND  = GND
  DY7  PE1_TX_DN(13)  OUT  = P3E_CPU0_PE1_PCH_TXN<13>
  DY9  PE3_TX_DP(4)  OUT  = P3E_CPU0_PE3_OCP_TXP<4>
  DY11  PE3_TX_DN(3)  OUT  = P3E_CPU0_PE3_OCP_TXN<3>
  DY13  PE1_RX_DP(13)  IN  = P3E_CPU0_PE1_PCH_RXP<13>
  DY15  PE1_RX_DN(14)  IN  = P3E_CPU0_PE1_PCH_RXN<14>
  DY17  PE3_RX_DP(0)  IN  = P3E_CPU0_PE3_OCP_RXP<0>
  DY19  VSS(54)  GROUND  = GND
  DY21  DDR3_DQ(58)  BI  = M_D_DQ<58>
  DY23  VSS(53)  GROUND  = GND
  DY25  DDR4_DQ(54)  BI  = M_E_DQ<54>
  DY27  DDR4_DQ(52)  BI  = M_E_DQ<52>
  DY29  VSS(52)  GROUND  = GND
  DY31  DDR4_DQ(46)  BI  = M_E_DQ<46>
  DY33  DDR4_DQ(44)  BI  = M_E_DQ<44>
  DY35  VSS(51)  GROUND  = GND
  DY37  DDR3_DQ(38)  BI  = M_D_DQ<38>
  DY39  DDR3_DQ(36)  BI  = M_D_DQ<36>
  DY41  VSS(50)  GROUND  = GND
  DY45  VSS(1215)  GROUND  = GND
  DY47  VSS(1216)  GROUND  = GND
  DY49  VSS(1217)  GROUND  = GND
  DY51  VSS(1218)  GROUND  = GND
  DY53  VSS(1219)  GROUND  = GND
  DY55  VSS(1220)  GROUND  = GND
  DY57  VSS(1221)  GROUND  = GND
  DY59  VSS(1222)  GROUND  = GND
  DY61  VSS(1223)  GROUND  = GND
  DY63  VSS(1224)  GROUND  = GND
  DY65  DDR4_ECC(3)  BI  = M_E_ECC<3>
  DY67  DDR4_DQS_DP(8)  BI  = M_E_DQS_DP<8>
  DY69  DDR4_ECC(0)  BI  = M_E_ECC<0>
  DY71  VSS(49)  GROUND  = GND
  DY73  DDR4_DQS_DP(12)  BI  = M_E_DQS_DP<12>
  DY75  VSS(48)  GROUND  = GND
  DY77  DDR4_DQ(18)  BI  = M_E_DQ<18>
  DY79  DDR4_DQS_DN(11)  BI  = M_E_DQS_DN<11>
  DY81  DDR4_DQ(20)  BI  = M_E_DQ<20>
  DY83  DDR3_DQ(11)  BI  = M_D_DQ<11>
  DY85  VSS(1242)  GROUND  = GND
  E2  RSVD(283)  BI  = TP_CPU0_RSVD_283
  E4  RSVD(282)  BI  = TP_CPU0_RSVD_282
  E6  VSS(1154)  GROUND  = GND
  E8  VSS(1153)  GROUND  = GND
  E10  UPI1_TX_DP(8)  OUT  = UPI_CPU0_CPU1_P1P1_DP<11>
  E12  UPI1_TX_DN(10)  OUT  = UPI_CPU0_CPU1_P1P1_DN<9>
  E14  UPI1_TX_DP(12)  OUT  = UPI_CPU0_CPU1_P1P1_DP<7>
  E16  VSS(1152)  GROUND  = GND
  E18  VSS(1151)  GROUND  = GND
  E20  VSS(1150)  GROUND  = GND
  E22  VSS(1149)  GROUND  = GND
  E24  RSVD(281)  BI  = TP_CPU0_RSVD_281
  E26  DDR1_DQ(51)  BI  = M_B_DQ<51>
  E28  DDR1_DQS_DP(6)  BI  = M_B_DQS_DP<6>
  E30  DDR1_DQ(52)  BI  = M_B_DQ<52>
  E32  DDR1_DQ(43)  BI  = M_B_DQ<43>
  E34  DDR1_DQS_DP(5)  BI  = M_B_DQS_DP<5>
  E36  DDR1_DQ(44)  BI  = M_B_DQ<44>
  E38  DDR0_DQ(35)  BI  = M_A_DQ<35>
  E40  DDR0_DQS_DP(4)  BI  = M_A_DQS_DP<4>
  E42  DDR0_DQ(36)  BI  = M_A_DQ<36>
  E46  VCCD012(3)  POWER  = PVDDQ_ABC
  E48  VCCD012(4)  POWER  = PVDDQ_ABC
  E50  VCCD012(5)  POWER  = PVDDQ_ABC
  E52  VCCD012(6)  POWER  = PVDDQ_ABC
  E54  VCCD012(7)  POWER  = PVDDQ_ABC
  E56  VCCD012(8)  POWER  = PVDDQ_ABC
  E58  VCCD012(9)  POWER  = PVDDQ_ABC
  E60  VCCD012(10)  POWER  = PVDDQ_ABC
  E62  VCCD012(11)  POWER  = PVDDQ_ABC
  E64  VCCD012(12)  POWER  = PVDDQ_ABC
  E66  VSS(1228)  GROUND  = GND
  E72  VSS(1148)  GROUND  = GND
  E74  VSS(1147)  GROUND  = GND
  E76  VSS(1146)  GROUND  = GND
  E78  DDR1_DQ(22)  BI  = M_B_DQ<22>
  E80  DDR1_DQ(16)  BI  = M_B_DQ<16>
  E82  VSS(1244)  GROUND  = GND
  E84  RSVD(280)  BI  = TP_CPU0_RSVD_280
  EA4  RSVD(20)  BI  = TP_CPU0_RSVD_20
  EA6  VSS(47)  GROUND  = GND
  EA8  PE1_TX_DN(14)  OUT  = P3E_CPU0_PE1_PCH_TXN<14>
  EA10  PE3_TX_DP(3)  OUT  = P3E_CPU0_PE3_OCP_TXP<3>
  EA12  VCCIO(67)  POWER  = PVCCIO_CPU0
  EA14  VSS(1225)  GROUND  = GND
  EA16  VSS(45)  GROUND  = GND
  EA18  PE3_RX_DN(0)  IN  = P3E_CPU0_PE3_OCP_RXN<0>
  EA20  VSS(44)  GROUND  = GND
  EA22  VSS(43)  GROUND  = GND
  EA24  DDR4_DQ(50)  BI  = M_E_DQ<50>
  EA26  DDR4_DQS_DN(15)  BI  = M_E_DQS_DN<15>
  EA28  DDR4_DQ(53)  BI  = M_E_DQ<53>
  EA30  DDR4_DQ(42)  BI  = M_E_DQ<42>
  EA32  DDR4_DQS_DN(14)  BI  = M_E_DQS_DN<14>
  EA34  DDR4_DQ(45)  BI  = M_E_DQ<45>
  EA36  DDR3_DQ(34)  BI  = M_D_DQ<34>
  EA38  DDR3_DQS_DN(13)  BI  = M_D_DQS_DN<13>
  EA40  DDR3_DQ(37)  BI  = M_D_DQ<37>
  EA42  VSS(42)  GROUND  = GND
  EA44  RSVD(19)  BI  = TP_CPU0_RSVD_19
  EA46  DDR3_MA(17)  OUT  = M_D_MA<17>
  EA48  DDR3_ODT(3)  OUT  = M_D_ODT<3>
  EA50  DDR3_ODT(2)  OUT  = M_D_ODT<2>
  EA52  DDR3_MA(16)  OUT  = M_D_MA<16>
  EA54  DDR3_BA(1)  OUT  = M_D_BA<1>
  EA56  DDR3_CLK_DP(2)  OUT  = M_D_CLK_DP<2>
  EA58  DDR3_MA(5)  OUT  = M_D_MA<5>
  EA60  DDR3_MA(7)  OUT  = M_D_MA<7>
  EA62  DDR3_CKE(2)  OUT  = M_D_CKE<2>
  EA64  VSS(41)  GROUND  = GND
  EA66  DDR4_ECC(7)  BI  = M_E_ECC<7>
  EA68  DDR4_ECC(1)  BI  = M_E_ECC<1>
  EA70  VSS(40)  GROUND  = GND
  EA72  DDR4_DQ(30)  BI  = M_E_DQ<30>
  EA74  DDR4_DQ(28)  BI  = M_E_DQ<28>
  EA76  VSS(39)  GROUND  = GND
  EA78  VSS(38)  GROUND  = GND
  EA80  VSS(37)  GROUND  = GND
  EA82  VSS(36)  GROUND  = GND
  EA84  VSS(1241)  GROUND  = GND
  EB3  RSVD(18)  BI  = TP_CPU0_RSVD_18
  EB5  RSVD(17)  BI  = TP_CPU0_RSVD_17
  EB7  PE1_TX_DP(14)  OUT  = P3E_CPU0_PE1_PCH_TXP<14>
  EB9  PE3_TX_DN(4)  OUT  = P3E_CPU0_PE3_OCP_TXN<4>
  EB11  PE3_TX_DP(2)  OUT  = P3E_CPU0_PE3_OCP_TXP<2>
  EB13  VSS(35)  GROUND  = GND
  EB15  VCCIO(68)  POWER  = PVCCIO_CPU0
  EB21  DDR3_DQ(59)  BI  = M_D_DQ<59>
  EB23  VSS(33)  GROUND  = GND
  EB25  VSS(32)  GROUND  = GND
  EB27  VSS(31)  GROUND  = GND
  EB29  VSS(30)  GROUND  = GND
  EB31  VSS(29)  GROUND  = GND
  EB33  VSS(28)  GROUND  = GND
  EB35  VSS(27)  GROUND  = GND
  EB37  VSS(26)  GROUND  = GND
  EB39  VSS(25)  GROUND  = GND
  EB41  VSS(24)  GROUND  = GND
  EB45  DDR3_CS_N(7)  OUT  = M_D_CS_N<7>
  EB47  DDR3_CS_N(3)  OUT  = M_D_CS_N<3>
  EB49  DDR3_CS_N(5)  OUT  = M_D_CS_N<5>
  EB51  DDR3_CS_N(4)  OUT  = M_D_CS_N<4>
  EB53  DDR3_MA(0)  OUT  = M_D_MA<0>
  EB55  DDR3_CLK_DP(0)  OUT  = M_D_CLK_DP<0>
  EB57  DDR3_MA(3)  OUT  = M_D_MA<3>
  EB59  DDR3_MA(8)  OUT  = M_D_MA<8>
  EB61  DDR3_MA(11)  OUT  = M_D_MA<11>
  EB63  DDR3_CKE(3)  OUT  = M_D_CKE<3>
  EB65  VSS(23)  GROUND  = GND
  EB67  DDR4_DQS_DN(8)  BI  = M_E_DQS_DN<8>
  EB69  VSS(22)  GROUND  = GND
  EB71  DDR4_DQ(26)  BI  = M_E_DQ<26>
  EB73  DDR4_DQS_DN(12)  BI  = M_E_DQS_DN<12>
  EB75  DDR4_DQ(29)  BI  = M_E_DQ<29>
  EB77  DDR4_DQ(19)  BI  = M_E_DQ<19>
  EB79  DDR4_DQS_DP(2)  BI  = M_E_DQS_DP<2>
  EB81  DDR4_DQ(21)  BI  = M_E_DQ<21>
  EB83  VSS(1240)  GROUND  = GND
  EB85  RSVD(16)  BI  = TP_CPU0_RSVD_16
  EC4  RSVD(14)  BI  = TP_CPU0_RSVD_14
  EC6  VSS(1237)  GROUND  = GND
  EC8  PE1_TX_DP(15)  OUT  = P3E_CPU0_PE1_PCH_TXP<15>
  EC10  VSS(21)  GROUND  = GND
  EC12  PE3_TX_DN(2)  OUT  = P3E_CPU0_PE3_OCP_TXN<2>
  EC14  PE3_TX_DP(0)  OUT  = P3E_CPU0_PE3_OCP_TXP<0>
  EC16  RSVD(15)  BI  = TP_CPU0_RSVD_15
  EC22  DDR3_DQ(62)  BI  = M_D_DQ<62>
  EC24  DDR4_DQ(51)  BI  = M_E_DQ<51>
  EC26  DDR4_DQS_DP(6)  BI  = M_E_DQS_DP<6>
  EC28  DDR4_DQ(48)  BI  = M_E_DQ<48>
  EC30  DDR4_DQ(43)  BI  = M_E_DQ<43>
  EC32  DDR4_DQS_DP(5)  BI  = M_E_DQS_DP<5>
  EC34  DDR4_DQ(40)  BI  = M_E_DQ<40>
  EC36  DDR3_DQ(35)  BI  = M_D_DQ<35>
  EC38  DDR3_DQS_DP(4)  BI  = M_D_DQS_DP<4>
  EC40  DDR3_DQ(32)  BI  = M_D_DQ<32>
  EC42  VSS(1238)  GROUND  = GND
  EC44  RSVD(13)  BI  = TP_CPU0_RSVD_13
  EC46  VCCD345(11)  POWER  = PVDDQ_DEF
  EC48  VCCD345(10)  POWER  = PVDDQ_DEF
  EC50  VCCD345(9)  POWER  = PVDDQ_DEF
  EC52  VCCD345(8)  POWER  = PVDDQ_DEF
  EC54  VCCD345(7)  POWER  = PVDDQ_DEF
  EC56  VCCD345(6)  POWER  = PVDDQ_DEF
  EC58  VCCD345(5)  POWER  = PVDDQ_DEF
  EC60  VCCD345(4)  POWER  = PVDDQ_DEF
  EC62  VCCD345(3)  POWER  = PVDDQ_DEF
  EC70  VSS(20)  GROUND  = GND
  EC72  VSS(19)  GROUND  = GND
  EC74  VSS(18)  GROUND  = GND
  EC76  VSS(17)  GROUND  = GND
  EC78  DDR4_DQ(23)  BI  = M_E_DQ<23>
  EC80  DDR4_DQ(17)  BI  = M_E_DQ<17>
  EC82  VSS(1236)  GROUND  = GND
  EC84  RSVD(12)  BI  = TP_CPU0_RSVD_12
  ED5  RSVD(10)  BI  = TP_CPU0_RSVD_10
  ED7  VSS(1234)  GROUND  = GND
  ED9  PE1_TX_DN(15)  OUT  = P3E_CPU0_PE1_PCH_TXN<15>
  ED11  VSS(16)  GROUND  = GND
  ED13  PE3_TX_DP(1)  OUT  = P3E_CPU0_PE3_OCP_TXP<1>
  ED15  VSS(15)  GROUND  = GND
  ED23  VSS(14)  GROUND  = GND
  ED25  DDR4_DQ(55)  BI  = M_E_DQ<55>
  ED27  DDR4_DQ(49)  BI  = M_E_DQ<49>
  ED29  VSS(13)  GROUND  = GND
  ED31  DDR4_DQ(47)  BI  = M_E_DQ<47>
  ED33  DDR4_DQ(41)  BI  = M_E_DQ<41>
  ED35  VSS(12)  GROUND  = GND
  ED37  DDR3_DQ(39)  BI  = M_D_DQ<39>
  ED39  DDR3_DQ(33)  BI  = M_D_DQ<33>
  ED41  VSS(1235)  GROUND  = GND
  ED45  RSVD(11)  BI  = TP_CPU0_RSVD_11
  ED47  DDR3_CS_N(2)  OUT  = M_D_CS_N<2>
  ED49  DDR3_CS_N(1)  OUT  = M_D_CS_N<1>
  ED51  DDR3_MA(14)  OUT  = M_D_MA<14>
  ED53  DDR3_PAR  OUT  = M_D_PAR
  ED55  DDR3_CLK_DN(0)  OUT  = M_D_CLK_DN<0>
  ED57  DDR3_MA(1)  OUT  = M_D_MA<1>
  ED59  DDR3_MA(4)  OUT  = M_D_MA<4>
  ED61  DDR3_BG(0)  OUT  = M_D_BG<0>
  ED63  DDR3_ALERT_N  IN  = M_D_ALERT_N
  ED69  VSS(1229)  GROUND  = GND
  ED71  DDR4_DQ(27)  BI  = M_E_DQ<27>
  ED73  DDR4_DQS_DP(3)  BI  = M_E_DQS_DP<3>
  ED75  DDR4_DQ(24)  BI  = M_E_DQ<24>
  ED77  VSS(11)  GROUND  = GND
  ED79  DDR4_DQS_DN(2)  BI  = M_E_DQS_DN<2>
  ED81  VSS(1233)  GROUND  = GND
  ED83  RSVD(9)  BI  = TP_CPU0_RSVD_9
  EE6  RSVD(6)  BI  = TP_CPU0_RSVD_6
  EE8  VSS(1231)  GROUND  = GND
  EE10  VCCIO(0)  POWER  = PVCCIO_CPU0
  EE12  PE3_TX_DN(1)  OUT  = P3E_CPU0_PE3_OCP_TXN<1>
  EE14  PE3_TX_DN(0)  OUT  = P3E_CPU0_PE3_OCP_TXN<0>
  EE16  RSVD(8)  BI  = TP_CPU0_RSVD_8
  EE24  VSS(10)  GROUND  = GND
  EE26  DDR4_DQS_DN(6)  BI  = M_E_DQS_DN<6>
  EE28  VSS(9)  GROUND  = GND
  EE30  VSS(8)  GROUND  = GND
  EE32  DDR4_DQS_DN(5)  BI  = M_E_DQS_DN<5>
  EE34  VSS(7)  GROUND  = GND
  EE36  VSS(6)  GROUND  = GND
  EE38  DDR3_DQS_DN(4)  BI  = M_D_DQS_DN<4>
  EE40  VSS(1232)  GROUND  = GND
  EE44  VCCD345(50)  POWER  = PVDDQ_DEF
  EE46  RSVD(7)  BI  = TP_CPU0_RSVD_7
  EE48  DDR3_ODT(1)  OUT  = M_D_ODT<1>
  EE50  DDR3_ODT(0)  OUT  = M_D_ODT<0>
  EE52  DDR3_BA(0)  OUT  = M_D_BA<0>
  EE54  DDR3_CLK_DP(1)  OUT  = M_D_CLK_DP<1>
  EE56  DDR3_CLK_DP(3)  OUT  = M_D_CLK_DP<3>
  EE58  DDR3_MA(2)  OUT  = M_D_MA<2>
  EE60  DDR3_MA(6)  OUT  = M_D_MA<6>
  EE62  DDR3_CKE(0)  OUT  = M_D_CKE<0>
  EE70  VSS(5)  GROUND  = GND
  EE72  DDR4_DQ(31)  BI  = M_E_DQ<31>
  EE74  DDR4_DQ(25)  BI  = M_E_DQ<25>
  EE76  VSS(4)  GROUND  = GND
  EE78  VSS(3)  GROUND  = GND
  EE80  VSS(1230)  GROUND  = GND
  EE82  RSVD(5)  BI  = TP_CPU0_RSVD_5
  EE84  RSVD(4)  BI  = TP_CPU0_RSVD_4
  EF45  VCCD345(49)  POWER  = PVDDQ_DEF
  EF47  RSVD(3)  BI  = TP_CPU0_RSVD_3
  EF49  VCCD345(2)  POWER  = PVDDQ_DEF
  EF51  DDR3_CS_N(0)  OUT  = M_D_CS_N<0>
  EF53  VCCD345(1)  POWER  = PVDDQ_DEF
  EF55  DDR3_CLK_DN(1)  OUT  = M_D_CLK_DN<1>
  EF57  DDR3_CLK_DN(3)  OUT  = M_D_CLK_DN<3>
  EF59  VCCD345(0)  POWER  = PVDDQ_DEF
  EF61  DDR3_MA(9)  OUT  = M_D_MA<9>
  EF63  DDR3_CKE(1)  OUT  = M_D_CKE<1>
  EF71  VSS(2)  GROUND  = GND
  EF73  DDR4_DQS_DN(3)  BI  = M_E_DQS_DN<3>
  EF75  VSS(1)  GROUND  = GND
  EF77  RSVD(2)  BI  = TP_CPU0_RSVD_2
  EF79  VSS(0)  GROUND  = GND
  EF81  RSVD(1)  BI  = TP_CPU0_RSVD_1
  EF83  RSVD(0)  BI  = TP_CPU0_RSVD_0
  F3  RSVD(279)  BI  = TP_CPU0_RSVD_279
  F5  VSS(1145)  GROUND  = GND
  F7  UPI1_TX_DP(4)  OUT  = UPI_CPU0_CPU1_P1P1_DP<15>
  F9  UPI1_TX_DP(7)  OUT  = UPI_CPU0_CPU1_P1P1_DP<12>
  F11  UPI1_TX_DN(8)  OUT  = UPI_CPU0_CPU1_P1P1_DN<11>
  F13  UPI1_TX_DP(11)  OUT  = UPI_CPU0_CPU1_P1P1_DP<8>
  F15  UPI1_TX_DN(13)  OUT  = UPI_CPU0_CPU1_P1P1_DN<6>
  F17  VSS(1144)  GROUND  = GND
  F19  VSS(1143)  GROUND  = GND
  F21  UPI1_TX_DN(18)  OUT  = UPI_CPU0_CPU1_P1P1_DN<1>
  F23  RSVD(278)  BI  = TP_CPU0_RSVD_278
  F25  VSS(1142)  GROUND  = GND
  F27  DDR1_DQ(55)  BI  = M_B_DQ<55>
  F29  DDR1_DQ(53)  BI  = M_B_DQ<53>
  F31  VSS(1141)  GROUND  = GND
  F33  DDR1_DQ(47)  BI  = M_B_DQ<47>
  F35  DDR1_DQ(45)  BI  = M_B_DQ<45>
  F37  VSS(1140)  GROUND  = GND
  F39  DDR0_DQ(39)  BI  = M_A_DQ<39>
  F41  DDR0_DQ(37)  BI  = M_A_DQ<37>
  F43  VSS(1139)  GROUND  = GND
  F45  DDR0_CS_N(6)  OUT  = M_A_CS_N<6>
  F47  DDR0_CS_N(3)  OUT  = M_A_CS_N<3>
  F49  DDR0_CS_N(1)  OUT  = M_A_CS_N<1>
  F51  DDR0_MA(14)  OUT  = M_A_MA<14>
  F53  DDR0_MA(0)  OUT  = M_A_MA<0>
  F55  DDR0_CLK_DN(0)  OUT  = M_A_CLK_DN<0>
  F57  DDR0_MA(1)  OUT  = M_A_MA<1>
  F59  DDR0_MA(5)  OUT  = M_A_MA<5>
  F61  DDR0_MA(9)  OUT  = M_A_MA<9>
  F63  DDR0_BG(1)  OUT  = M_A_BG<1>
  F65  RSVD(277)  BI  = TP_CPU0_RSVD_277
  F67  VSS(1138)  GROUND  = GND
  F69  VSS(1137)  GROUND  = GND
  F71  DDR1_DQ(27)  BI  = M_B_DQ<27>
  F73  DDR1_DQS_DP(3)  BI  = M_B_DQS_DP<3>
  F75  DDR1_DQ(28)  BI  = M_B_DQ<28>
  F77  DDR1_DQ(18)  BI  = M_B_DQ<18>
  F79  DDR1_DQS_DP(11)  BI  = M_B_DQS_DP<11>
